(kicad_pcb
	(version 20241229)
	(generator "pcbnew")
	(generator_version "9.0")
	(general
		(thickness 1.599998)
		(legacy_teardrops no)
	)
	(paper "A4")
	(title_block
		(title "Artix - Datacenter Secure Control Module (DC-SCM)")
		(date "2024-11-06")
		(rev "1.1.3")
		(comment 9 "footprints 215-218 of 544")
	)
	(layers
		(0 "F.Cu" signal)
		(4 "In1.Cu" signal)
		(6 "In2.Cu" signal)
		(8 "In3.Cu" signal)
		(10 "In4.Cu" signal)
		(12 "In5.Cu" signal)
		(14 "In6.Cu" signal)
		(2 "B.Cu" signal)
		(9 "F.Adhes" user "F.Adhesive")
		(11 "B.Adhes" user "B.Adhesive")
		(13 "F.Paste" user)
		(15 "B.Paste" user)
		(5 "F.SilkS" user "F.Silkscreen")
		(7 "B.SilkS" user "B.Silkscreen")
		(1 "F.Mask" user)
		(3 "B.Mask" user)
		(17 "Dwgs.User" user "User.Drawings")
		(19 "Cmts.User" user "User.Comments")
		(21 "Eco1.User" user "User.Eco1")
		(23 "Eco2.User" user "User.Eco2")
		(25 "Edge.Cuts" user)
		(27 "Margin" user)
		(31 "F.CrtYd" user "F.Courtyard")
		(29 "B.CrtYd" user "B.Courtyard")
		(35 "F.Fab" user)
		(33 "B.Fab" user)
	)
	(footprint "antmicro-footprints:VQFN-20_1EP_4.5x2.5mm_P0.5mm"
		(layer "F.Cu")
		(at 86.64 166.015)
		(property "Reference" "U21"
			(at 0.66 -1.815 0)
			(layer "F.SilkS")
			(effects
				(font
					(size 0.7 0.7)
					(thickness 0.15)
				)
				(justify left bottom)
			)
		)
		(property "Value" "LSF0108RKSR"
			(at 0.689 2.959 0)
			(layer "F.Fab")
			(effects
				(font
					(size 0.7 0.7)
					(thickness 0.15)
				)
				(justify left bottom)
			)
		)
		(property "Datasheet" "https://www.ti.com/lit/ds/symlink/lsf0108.pdf?ts=1686550470995&ref_url=https%253A%252F%252Fwww.ti.com%252Fproduct%252FLSF0108%252Fpart-details%252FLSF0108RKSR"
			(at 0 0 0)
			(layer "F.Fab")
			(hide yes)
			(effects
				(font
					(size 1.27 1.27)
					(thickness 0.15)
				)
			)
		)
		(property "Description" "Voltage Level Translator, 8 Input, 1.5 ns, 0 V to 5 V, VQFN-20"
			(at 0 0 0)
			(layer "F.Fab")
			(hide yes)
			(effects
				(font
					(size 1.27 1.27)
					(thickness 0.15)
				)
			)
		)
		(property "Author" "Antmicro"
			(at 0 0 0)
			(layer "F.Fab")
			(hide yes)
			(effects
				(font
					(size 1 1)
					(thickness 0.15)
				)
			)
		)
		(property "License" "Apache-2.0"
			(at 0 0 0)
			(layer "F.Fab")
			(hide yes)
			(effects
				(font
					(size 1 1)
					(thickness 0.15)
				)
			)
		)
		(property "MPN" "LSF0108RKSR"
			(at 0 0 0)
			(layer "F.Fab")
			(hide yes)
			(effects
				(font
					(size 1 1)
					(thickness 0.15)
				)
			)
		)
		(property "Manufacturer" "Texas Instruments"
			(at 0 0 0)
			(layer "F.Fab")
			(hide yes)
			(effects
				(font
					(size 1 1)
					(thickness 0.15)
				)
			)
		)
		(sheetname "/Interfaces/")
		(sheetfile "interfaces.kicad_sch")
		(attr smd exclude_from_pos_files exclude_from_bom dnp)
		(fp_line
			(start -2.25 -1.25)
			(end -2.25 -0.5)
			(stroke
				(width 0.15)
				(type solid)
			)
			(layer "F.SilkS")
		)
		(fp_line
			(start -2.249 1.25)
			(end -2 1.25)
			(stroke
				(width 0.15)
				(type solid)
			)
			(layer "F.SilkS")
		)
		(fp_line
			(start -2.001 -1.25)
			(end -2.25 -1.25)
			(stroke
				(width 0.15)
				(type solid)
			)
			(layer "F.SilkS")
		)
		(fp_line
			(start 2.249 -1.25)
			(end 2 -1.25)
			(stroke
				(width 0.15)
				(type solid)
			)
			(layer "F.SilkS")
		)
		(fp_line
			(start 2.249 -1.25)
			(end 2.249 -0.5)
			(stroke
				(width 0.15)
				(type solid)
			)
			(layer "F.SilkS")
		)
		(fp_line
			(start 2.249 1.249)
			(end 2 1.249)
			(stroke
				(width 0.15)
				(type solid)
			)
			(layer "F.SilkS")
		)
		(fp_line
			(start 2.249 1.249)
			(end 2.249 0.5)
			(stroke
				(width 0.15)
				(type solid)
			)
			(layer "F.SilkS")
		)
		(fp_rect
			(start -2.711 -1.71)
			(end 2.708 1.709)
			(stroke
				(width 0.05)
				(type solid)
			)
			(fill no)
			(layer "F.CrtYd")
		)
		(fp_line
			(start -2.25 1.249)
			(end -2.25 -1.25)
			(stroke
				(width 0.15)
				(type solid)
			)
			(layer "F.Fab")
		)
		(fp_line
			(start 2.249 -1.25)
			(end -2.25 -1.25)
			(stroke
				(width 0.15)
				(type solid)
			)
			(layer "F.Fab")
		)
		(fp_line
			(start 2.249 1.249)
			(end -2.25 1.249)
			(stroke
				(width 0.15)
				(type solid)
			)
			(layer "F.Fab")
		)
		(fp_line
			(start 2.249 1.249)
			(end 2.249 -1.25)
			(stroke
				(width 0.15)
				(type solid)
			)
			(layer "F.Fab")
		)
		(pad "" smd roundrect
			(at -0.76 0)
			(size 1.31 0.95)
			(layers "F.Paste")
			(roundrect_rratio 0.05)
		)
		(pad "" smd roundrect
			(at 0.76 0)
			(size 1.31 0.95)
			(layers "F.Paste")
			(roundrect_rratio 0.05)
		)
		(pad "1" smd roundrect
			(at -2.15 0.25 90)
			(size 0.25 0.8)
			(layers "F.Cu" "F.Mask" "F.Paste")
			(roundrect_rratio 0.2)
			(net 1 "GND")
			(pinfunction "GND")
			(pintype "power_in")
		)
		(pad "2" smd roundrect
			(at -1.75 1.15)
			(size 0.25 0.8)
			(layers "F.Cu" "F.Mask" "F.Paste")
			(roundrect_rratio 0.2)
			(net 5 "VCC1V8")
			(pinfunction "VREF_{A}")
			(pintype "power_in")
		)
		(pad "3" smd roundrect
			(at -1.25 1.15)
			(size 0.25 0.8)
			(layers "F.Cu" "F.Mask" "F.Paste")
			(roundrect_rratio 0.2)
			(net 584 "ESPI_CLK_1V8")
			(pinfunction "A1")
			(pintype "bidirectional")
		)
		(pad "4" smd roundrect
			(at -0.75 1.15)
			(size 0.25 0.8)
			(layers "F.Cu" "F.Mask" "F.Paste")
			(roundrect_rratio 0.2)
			(net 583 "ESPI_CS0_N_1V8")
			(pinfunction "A2")
			(pintype "bidirectional")
		)
		(pad "5" smd roundrect
			(at -0.25 1.15)
			(size 0.25 0.8)
			(layers "F.Cu" "F.Mask" "F.Paste")
			(roundrect_rratio 0.2)
			(net 582 "ESPI_ALERT_N_1V8")
			(pinfunction "A3")
			(pintype "bidirectional")
		)
		(pad "6" smd roundrect
			(at 0.25 1.15)
			(size 0.25 0.8)
			(layers "F.Cu" "F.Mask" "F.Paste")
			(roundrect_rratio 0.2)
			(net 581 "ESPI_RESET_N_1V8")
			(pinfunction "A4")
			(pintype "bidirectional")
		)
		(pad "7" smd roundrect
			(at 0.75 1.15)
			(size 0.25 0.8)
			(layers "F.Cu" "F.Mask" "F.Paste")
			(roundrect_rratio 0.2)
			(net 580 "ESPI_IO0_1V8")
			(pinfunction "A5")
			(pintype "bidirectional")
		)
		(pad "8" smd roundrect
			(at 1.25 1.15)
			(size 0.25 0.8)
			(layers "F.Cu" "F.Mask" "F.Paste")
			(roundrect_rratio 0.2)
			(net 579 "ESPI_IO1_1V8")
			(pinfunction "A6")
			(pintype "bidirectional")
		)
		(pad "9" smd roundrect
			(at 1.75 1.15)
			(size 0.25 0.8)
			(layers "F.Cu" "F.Mask" "F.Paste")
			(roundrect_rratio 0.2)
			(net 578 "ESPI_IO2_1V8")
			(pinfunction "A7")
			(pintype "bidirectional")
		)
		(pad "10" smd roundrect
			(at 2.15 0.25 90)
			(size 0.25 0.8)
			(layers "F.Cu" "F.Mask" "F.Paste")
			(roundrect_rratio 0.2)
			(net 577 "ESPI_IO3_1V8")
			(pinfunction "A8")
			(pintype "bidirectional")
		)
		(pad "11" smd roundrect
			(at 2.15 -0.25 90)
			(size 0.25 0.8)
			(layers "F.Cu" "F.Mask" "F.Paste")
			(roundrect_rratio 0.2)
			(net 68 "ESPI_IO3")
			(pinfunction "B8")
			(pintype "bidirectional")
		)
		(pad "12" smd roundrect
			(at 1.75 -1.15)
			(size 0.25 0.8)
			(layers "F.Cu" "F.Mask" "F.Paste")
			(roundrect_rratio 0.2)
			(net 67 "ESPI_IO2")
			(pinfunction "B7")
			(pintype "bidirectional")
		)
		(pad "13" smd roundrect
			(at 1.25 -1.15)
			(size 0.25 0.8)
			(layers "F.Cu" "F.Mask" "F.Paste")
			(roundrect_rratio 0.2)
			(net 66 "ESPI_IO1")
			(pinfunction "B6")
			(pintype "bidirectional")
		)
		(pad "14" smd roundrect
			(at 0.75 -1.15)
			(size 0.25 0.8)
			(layers "F.Cu" "F.Mask" "F.Paste")
			(roundrect_rratio 0.2)
			(net 65 "ESPI_IO0")
			(pinfunction "B5")
			(pintype "bidirectional")
		)
		(pad "15" smd roundrect
			(at 0.25 -1.15)
			(size 0.25 0.8)
			(layers "F.Cu" "F.Mask" "F.Paste")
			(roundrect_rratio 0.2)
			(net 64 "ESPI_RESET_N")
			(pinfunction "B4")
			(pintype "bidirectional")
		)
		(pad "16" smd roundrect
			(at -0.25 -1.15)
			(size 0.25 0.8)
			(layers "F.Cu" "F.Mask" "F.Paste")
			(roundrect_rratio 0.2)
			(net 63 "ESPI_ALERT_N")
			(pinfunction "B3")
			(pintype "bidirectional")
		)
		(pad "17" smd roundrect
			(at -0.75 -1.15)
			(size 0.25 0.8)
			(layers "F.Cu" "F.Mask" "F.Paste")
			(roundrect_rratio 0.2)
			(net 62 "ESPI_CS0_N")
			(pinfunction "B2")
			(pintype "bidirectional")
		)
		(pad "18" smd roundrect
			(at -1.25 -1.15)
			(size 0.25 0.8)
			(layers "F.Cu" "F.Mask" "F.Paste")
			(roundrect_rratio 0.2)
			(net 61 "ESPI_CLK")
			(pinfunction "B1")
			(pintype "bidirectional")
		)
		(pad "19" smd roundrect
			(at -1.75 -1.15)
			(size 0.25 0.8)
			(layers "F.Cu" "F.Mask" "F.Paste")
			(roundrect_rratio 0.2)
			(net 2 "VCC3V3")
			(pinfunction "VREF_{B}")
			(pintype "power_in")
		)
		(pad "20" smd roundrect
			(at -2.15 -0.25 90)
			(size 0.25 0.8)
			(layers "F.Cu" "F.Mask" "F.Paste")
			(roundrect_rratio 0.2)
			(net 312 "Net-(U21-EN)")
			(pinfunction "EN")
			(pintype "input")
		)
		(pad "21" smd roundrect
			(at 0 0)
			(size 3 1)
			(layers "F.Cu" "F.Mask")
			(roundrect_rratio 0.05)
			(net 1 "GND")
			(pinfunction "EP")
			(pintype "power_in")
		)
	)
	(footprint "antmicro-footprints:USON-6_1.45x1.0mm_P0.5mm_Texas_DRY6"
		(layer "F.Cu")
		(at 91.059 163.363 180)
		(property "Reference" "U22"
			(at 1.359 1.463 0)
			(layer "F.SilkS")
			(effects
				(font
					(size 0.7 0.7)
					(thickness 0.15)
				)
				(justify left bottom)
			)
		)
		(property "Value" "LSF0101DRYR"
			(at 7.416 2.156 180)
			(layer "F.Fab")
			(effects
				(font
					(size 0.7 0.7)
					(thickness 0.15)
				)
				(justify left bottom)
			)
		)
		(property "Datasheet" "https://www.ti.com/lit/ds/symlink/lsf0101.pdf?ts=1686656250822&ref_url=https%253A%252F%252Fwww.ti.com%252Fproduct%252FLSF0101%252Fpart-details%252FLSF0101DRYR"
			(at 0 0 180)
			(layer "F.Fab")
			(hide yes)
			(effects
				(font
					(size 1.27 1.27)
					(thickness 0.15)
				)
			)
		)
		(property "Description" "Voltage Level Translator, 1 Input, 1.5 ns, 0 V to 5 V, SON-6"
			(at 0 0 180)
			(layer "F.Fab")
			(hide yes)
			(effects
				(font
					(size 1.27 1.27)
					(thickness 0.15)
				)
			)
		)
		(property "Author" "Antmicro"
			(at 182.118 326.726 0)
			(layer "F.Fab")
			(hide yes)
			(effects
				(font
					(size 1 1)
					(thickness 0.15)
				)
			)
		)
		(property "License" "Apache-2.0"
			(at 182.118 326.726 0)
			(layer "F.Fab")
			(hide yes)
			(effects
				(font
					(size 1 1)
					(thickness 0.15)
				)
			)
		)
		(property "MPN" "LSF0101DRYR"
			(at 182.118 326.726 0)
			(layer "F.Fab")
			(hide yes)
			(effects
				(font
					(size 1 1)
					(thickness 0.15)
				)
			)
		)
		(property "Manufacturer" "Texas Instruments"
			(at 182.118 326.726 0)
			(layer "F.Fab")
			(hide yes)
			(effects
				(font
					(size 1 1)
					(thickness 0.15)
				)
			)
		)
		(sheetname "/Interfaces/")
		(sheetfile "interfaces.kicad_sch")
		(attr smd)
		(fp_line
			(start -0.211 1.275)
			(end 0.79 1.275)
			(stroke
				(width 0.15)
				(type solid)
			)
			(layer "F.SilkS")
		)
		(fp_line
			(start -0.211 -0.275)
			(end 0.79 -0.275)
			(stroke
				(width 0.15)
				(type solid)
			)
			(layer "F.SilkS")
		)
		(fp_rect
			(start -0.411 -0.326)
			(end 0.99 1.325)
			(stroke
				(width 0.05)
				(type solid)
			)
			(fill no)
			(layer "F.CrtYd")
		)
		(fp_line
			(start 0.79 1.225)
			(end 0.79 -0.226)
			(stroke
				(width 0.15)
				(type solid)
			)
			(layer "F.Fab")
		)
		(fp_line
			(start -0.211 1.225)
			(end 0.79 1.225)
			(stroke
				(width 0.15)
				(type solid)
			)
			(layer "F.Fab")
		)
		(fp_line
			(start -0.211 -0.226)
			(end 0.79 -0.226)
			(stroke
				(width 0.15)
				(type solid)
			)
			(layer "F.Fab")
		)
		(fp_line
			(start -0.211 -0.226)
			(end -0.211 1.225)
			(stroke
				(width 0.15)
				(type solid)
			)
			(layer "F.Fab")
		)
		(fp_text user "."
			(at -0.5 -0.6 180)
			(layer "F.SilkS")
			(effects
				(font
					(size 1 1)
					(thickness 0.15)
				)
			)
		)
		(pad "1" smd roundrect
			(at 0 0 180)
			(size 0.42 0.3)
			(layers "F.Cu" "F.Mask" "F.Paste")
			(roundrect_rratio 0)
			(chamfer_ratio 0.3)
			(chamfer top_left)
			(net 1 "GND")
			(pinfunction "GND")
			(pintype "power_in")
		)
		(pad "2" smd rect
			(at -0.006 0.498 180)
			(size 0.41 0.3)
			(layers "F.Cu" "F.Mask" "F.Paste")
			(net 5 "VCC1V8")
			(pinfunction "VREF_{A}")
			(pintype "input")
		)
		(pad "3" smd rect
			(at -0.006 0.998 180)
			(size 0.41 0.3)
			(layers "F.Cu" "F.Mask" "F.Paste")
			(net 576 "ESPI_CS1_N_1V8")
			(pinfunction "A1")
			(pintype "bidirectional")
		)
		(pad "4" smd rect
			(at 0.583 0.998 180)
			(size 0.41 0.3)
			(layers "F.Cu" "F.Mask" "F.Paste")
			(net 69 "ESPI_CS1_N")
			(pinfunction "B1")
			(pintype "bidirectional")
		)
		(pad "5" smd rect
			(at 0.583 0.498 180)
			(size 0.41 0.3)
			(layers "F.Cu" "F.Mask" "F.Paste")
			(net 2 "VCC3V3")
			(pinfunction "VREF_{B}")
			(pintype "input")
		)
		(pad "6" smd rect
			(at 0.583 0 180)
			(size 0.41 0.3)
			(layers "F.Cu" "F.Mask" "F.Paste")
			(net 338 "Net-(U22-EN)")
			(pinfunction "EN")
			(pintype "input")
		)
	)
	(footprint "antmicro-footprints:C_0402_1005Metric"
		(layer "F.Cu")
		(at 78.265 67.7 90)
		(descr "Capacitor SMD 0402")
		(tags "capacitor SMD 0402")
		(property "Reference" "C250"
			(at -1.3 -16.165 90)
			(layer "F.SilkS")
			(effects
				(font
					(size 0.7 0.7)
					(thickness 0.15)
				)
				(justify left bottom)
			)
		)
		(property "Value" "C_10u_0402"
			(at 0 1.4 90)
			(layer "F.Fab")
			(effects
				(font
					(size 0.7 0.7)
					(thickness 0.15)
				)
				(justify left bottom)
			)
		)
		(property "Datasheet" "https://www.yageo.com/en/Chart/Download/pdf/CC0402MRX5R5BB106"
			(at 0 0 90)
			(layer "F.Fab")
			(hide yes)
			(effects
				(font
					(size 1.27 1.27)
					(thickness 0.15)
				)
			)
		)
		(property "Description" "SMD Multilayer Ceramic Capacitor, 10 µF, 6.3 V, 0402 [1005 Metric], ± 20%, X5R, CC Series"
			(at 0 0 90)
			(layer "F.Fab")
			(hide yes)
			(effects
				(font
					(size 1.27 1.27)
					(thickness 0.15)
				)
			)
		)
		(property "Author" "Antmicro"
			(at 145.965 -10.565 0)
			(layer "F.Fab")
			(hide yes)
			(effects
				(font
					(size 1 1)
					(thickness 0.15)
				)
			)
		)
		(property "Dielectric" ""
			(at 145.965 -10.565 0)
			(layer "F.Fab")
			(hide yes)
			(effects
				(font
					(size 1 1)
					(thickness 0.15)
				)
			)
		)
		(property "License" "Apache-2.0"
			(at 145.965 -10.565 0)
			(layer "F.Fab")
			(hide yes)
			(effects
				(font
					(size 1 1)
					(thickness 0.15)
				)
			)
		)
		(property "MPN" "CC0402MRX5R5BB106"
			(at 145.965 -10.565 0)
			(layer "F.Fab")
			(hide yes)
			(effects
				(font
					(size 1 1)
					(thickness 0.15)
				)
			)
		)
		(property "Manufacturer" "YAGEO"
			(at 145.965 -10.565 0)
			(layer "F.Fab")
			(hide yes)
			(effects
				(font
					(size 1 1)
					(thickness 0.15)
				)
			)
		)
		(property "Val" "10u"
			(at 145.965 -10.565 0)
			(layer "F.Fab")
			(hide yes)
			(effects
				(font
					(size 1 1)
					(thickness 0.15)
				)
			)
		)
		(property "Voltage" ""
			(at 145.965 -10.565 0)
			(layer "F.Fab")
			(hide yes)
			(effects
				(font
					(size 1 1)
					(thickness 0.15)
				)
			)
		)
		(sheetname "/Power supply/")
		(sheetfile "power-supply.kicad_sch")
		(attr smd)
		(fp_rect
			(start -0.925 -0.47)
			(end 0.925 0.47)
			(stroke
				(width 0.05)
				(type default)
			)
			(fill no)
			(layer "F.CrtYd")
		)
		(fp_line
			(start 0.504 -0.25)
			(end 0.504 0.248)
			(stroke
				(width 0.15)
				(type solid)
			)
			(layer "F.Fab")
		)
		(fp_line
			(start -0.494 -0.25)
			(end 0.504 -0.25)
			(stroke
				(width 0.15)
				(type solid)
			)
			(layer "F.Fab")
		)
		(fp_line
			(start 0.504 0.248)
			(end -0.494 0.248)
			(stroke
				(width 0.15)
				(type solid)
			)
			(layer "F.Fab")
		)
		(fp_line
			(start -0.494 0.248)
			(end -0.494 -0.25)
			(stroke
				(width 0.15)
				(type solid)
			)
			(layer "F.Fab")
		)
		(pad "1" smd roundrect
			(at -0.48 0 90)
			(size 0.59 0.64)
			(layers "F.Cu" "F.Mask" "F.Paste")
			(roundrect_rratio 0.25)
			(net 1 "GND")
			(pintype "passive")
		)
		(pad "2" smd roundrect
			(at 0.48 0 90)
			(size 0.59 0.64)
			(layers "F.Cu" "F.Mask" "F.Paste")
			(roundrect_rratio 0.25)
			(net 573 "/Power supply/5V0_PG")
			(pintype "passive")
		)
	)
	(footprint "antmicro-footprints:TP_SMD_1mm"
		(layer "F.Cu")
		(at 69.175 88.35 -90)
		(property "Reference" "TP4"
			(at 0.25 0.675 180)
			(layer "F.SilkS")
			(effects
				(font
					(size 0.7 0.7)
					(thickness 0.15)
				)
				(justify right bottom)
			)
		)
		(property "Value" "TP_1mm_SMD"
			(at 0 1.4 90)
			(layer "F.Fab")
			(effects
				(font
					(size 0.7 0.7)
					(thickness 0.15)
				)
				(justify right bottom)
			)
		)
		(property "Description" "Test point 1mm SMD"
			(at 0 0 270)
			(layer "F.Fab")
			(hide yes)
			(effects
				(font
					(size 1.27 1.27)
					(thickness 0.15)
				)
			)
		)
		(property "Author" "Antmicro"
			(at -19.175 157.525 0)
			(layer "F.Fab")
			(hide yes)
			(effects
				(font
					(size 1 1)
					(thickness 0.15)
				)
			)
		)
		(property "License" "Apache-2.0"
			(at -19.175 157.525 0)
			(layer "F.Fab")
			(hide yes)
			(effects
				(font
					(size 1 1)
					(thickness 0.15)
				)
			)
		)
		(property "MPN" ""
			(at -19.175 157.525 0)
			(layer "F.Fab")
			(hide yes)
			(effects
				(font
					(size 1 1)
					(thickness 0.15)
				)
			)
		)
		(property "Manufacturer" ""
			(at -19.175 157.525 0)
			(layer "F.Fab")
			(hide yes)
			(effects
				(font
					(size 1 1)
					(thickness 0.15)
				)
			)
		)
		(sheetname "/Power supply/")
		(sheetfile "power-supply.kicad_sch")
		(attr exclude_from_pos_files exclude_from_bom)
		(fp_circle
			(center 0 0)
			(end 0.6 0)
			(stroke
				(width 0.05)
				(type default)
			)
			(fill no)
			(layer "F.CrtYd")
		)
		(pad "1" smd circle
			(at 0 0 270)
			(size 1 1)
			(layers "F.Cu" "F.Mask")
			(net 573 "/Power supply/5V0_PG")
			(pinfunction "1")
			(pintype "passive")
		)
	)
)
